(kicad_pcb
	(version 20260206)
	(generator "pcbnew")
	(generator_version "10.0")
	(general
		(thickness 1.6)
		(legacy_teardrops no)
	)
	(paper "A4")
	(title_block
		(title "dpb — 14545-sa.0730WZS0815.brd")
		(comment 1 "Honey Badger (Wiwynn) / footprints 932-938 of 1066")
	)
	(layers
		(0 "F.Cu" signal "TOP")
		(4 "In1.Cu" signal "L2GND")
		(6 "In2.Cu" signal "L3")
		(8 "In3.Cu" signal "L4VCC")
		(10 "In4.Cu" signal "L5VCC")
		(12 "In5.Cu" signal "L6")
		(14 "In6.Cu" signal "L7GND")
		(2 "B.Cu" signal "BOTTOM")
		(9 "F.Adhes" user "F.Adhesive")
		(11 "B.Adhes" user "B.Adhesive")
		(13 "F.Paste" user "Package Geometry/Pastemask Top")
		(15 "B.Paste" user "Package Geometry/Pastemask Bottom")
		(5 "F.SilkS" user "Ref Des/Silkscreen Top")
		(7 "B.SilkS" user "Ref Des/Silkscreen Bottom")
		(1 "F.Mask" user "Board Geometry/Soldermask Top")
		(3 "B.Mask" user "Board Geometry/Soldermask Bottom")
		(17 "Dwgs.User" user "User.Drawings")
		(19 "Cmts.User" user "User.Comments")
		(21 "Eco1.User" user "User.Eco1")
		(23 "Eco2.User" user "User.Eco2")
		(25 "Edge.Cuts" user "Board Geometry/Outline")
		(27 "Margin" user)
		(31 "F.CrtYd" user "Package Geometry/Place Bound Top")
		(29 "B.CrtYd" user "Package Geometry/Place Bound Bottom")
		(35 "F.Fab" user "Ref Des/Assembly Top")
		(33 "B.Fab" user "Ref Des/Assembly Bottom")
	)
	(footprint ""
		(layer "F.Cu")
		(at 229.488746 -29.2227 -90)
		(property "Reference" "PR4"
			(at 0 0 270)
			(layer "F.SilkS")
			(hide yes)
			(effects
				(font
					(size 1.27 1.27)
				)
			)
		)
		(property "Value" "0R3J-0-U-GP"
			(at -0.0254 -2.5146 270)
			(unlocked yes)
			(layer "F.Fab")
			(hide yes)
			(effects
				(font
					(size 1.016 1.016)
					(thickness 0.1524)
				)
			)
		)
		(property "Device Type" "R603H22"
			(at -0.0254 -4.0386 270)
			(unlocked yes)
			(layer "F.Fab")
			(hide yes)
			(effects
				(font
					(size 1.016 1.016)
					(thickness 0.1524)
				)
			)
		)
		(duplicate_pad_numbers_are_jumpers no)
		(fp_line
			(start -0.4826 0)
			(end -0.2032 0)
			(stroke
				(width 0.2032)
				(type default)
			)
			(layer "F.SilkS")
		)
		(fp_line
			(start 0.2032 0)
			(end 0.4826 0)
			(stroke
				(width 0.2032)
				(type default)
			)
			(layer "F.SilkS")
		)
		(fp_rect
			(start -0.5842 1.3335)
			(end 0.5842 -1.3335)
			(stroke
				(width 0)
				(type default)
			)
			(fill no)
			(layer "F.CrtYd")
		)
		(fp_rect
			(start -0.5842 1.3335)
			(end 0.5842 -1.3335)
			(stroke
				(width 0)
				(type default)
			)
			(fill no)
			(layer "F.Fab")
		)
		(pad "1" smd custom
			(at 0 -0.762 270)
			(size 0.2159 0.2159)
			(layers "F.Cu" "F.Mask" "F.Paste")
			(net "P5VA_VBST")
			(options
				(clearance outline)
				(anchor circle)
			)
			(primitives
				(gr_poly
					(pts
						(arc
							(start -0.3302 -0.4318)
							(mid -0.402042 -0.402042)
							(end -0.4318 -0.3302)
						)
						(arc
							(start -0.4318 0.3302)
							(mid -0.402042 0.402042)
							(end -0.3302 0.4318)
						)
						(arc
							(start 0.3302 0.4318)
							(mid 0.402042 0.402042)
							(end 0.4318 0.3302)
						)
						(arc
							(start 0.4318 -0.3302)
							(mid 0.402042 -0.402042)
							(end 0.3302 -0.4318)
						)
					)
					(width 0)
					(fill yes)
				)
			)
		)
		(pad "2" smd custom
			(at 0 0.762 270)
			(size 0.2159 0.2159)
			(layers "F.Cu" "F.Mask" "F.Paste")
			(net "P5VA_VBST_NET")
			(options
				(clearance outline)
				(anchor circle)
			)
			(primitives
				(gr_poly
					(pts
						(arc
							(start -0.3302 -0.4318)
							(mid -0.402042 -0.402042)
							(end -0.4318 -0.3302)
						)
						(arc
							(start -0.4318 0.3302)
							(mid -0.402042 0.402042)
							(end -0.3302 0.4318)
						)
						(arc
							(start 0.3302 0.4318)
							(mid 0.402042 0.402042)
							(end 0.4318 0.3302)
						)
						(arc
							(start 0.4318 -0.3302)
							(mid 0.402042 -0.402042)
							(end 0.3302 -0.4318)
						)
					)
					(width 0)
					(fill yes)
				)
			)
		)
	)
	(footprint ""
		(layer "F.Cu")
		(at 197.357746 -285.3817 -90)
		(property "Reference" "R433"
			(at 0 0 270)
			(layer "F.SilkS")
			(hide yes)
			(effects
				(font
					(size 1.27 1.27)
				)
			)
		)
		(property "Value" "4K7R2J-2-GP"
			(at 0.064008 -3.993896 270)
			(unlocked yes)
			(layer "F.Fab")
			(hide yes)
			(effects
				(font
					(size 1.016 1.016)
					(thickness 0.1524)
				)
			)
		)
		(property "Device Type" "R402H16"
			(at 0.064008 -5.517896 270)
			(unlocked yes)
			(layer "F.Fab")
			(hide yes)
			(effects
				(font
					(size 1.016 1.016)
					(thickness 0.1524)
				)
			)
		)
		(duplicate_pad_numbers_are_jumpers no)
		(fp_line
			(start -0.508 -0.9398)
			(end -0.508 0.9398)
			(stroke
				(width 0.1524)
				(type default)
			)
			(layer "F.SilkS")
		)
		(fp_line
			(start 0.508 -0.9398)
			(end -0.508 -0.9398)
			(stroke
				(width 0.1524)
				(type default)
			)
			(layer "F.SilkS")
		)
		(fp_rect
			(start -0.508 0.9398)
			(end 0.508 -0.9398)
			(stroke
				(width 0)
				(type default)
			)
			(fill no)
			(layer "F.CrtYd")
		)
		(fp_rect
			(start -0.508 0.9398)
			(end 0.508 -0.9398)
			(stroke
				(width 0)
				(type default)
			)
			(fill no)
			(layer "F.Fab")
		)
		(pad "1" smd custom
			(at 0 -0.4445 270)
			(size 0.1397 0.1397)
			(layers "F.Cu" "F.Mask" "F.Paste")
			(net "P3V3")
			(options
				(clearance outline)
				(anchor circle)
			)
			(primitives
				(gr_poly
					(pts
						(arc
							(start -0.1778 -0.2794)
							(mid -0.249642 -0.249642)
							(end -0.2794 -0.1778)
						)
						(arc
							(start -0.2794 0.1778)
							(mid -0.249642 0.249642)
							(end -0.1778 0.2794)
						)
						(arc
							(start 0.1778 0.2794)
							(mid 0.249642 0.249642)
							(end 0.2794 0.1778)
						)
						(arc
							(start 0.2794 -0.1778)
							(mid 0.249642 -0.249642)
							(end 0.1778 -0.2794)
						)
					)
					(width 0)
					(fill yes)
				)
			)
		)
		(pad "2" smd custom
			(at 0 0.4445 270)
			(size 0.1397 0.1397)
			(layers "F.Cu" "F.Mask" "F.Paste")
			(net "SAS_EXP_B_PWR2")
			(options
				(clearance outline)
				(anchor circle)
			)
			(primitives
				(gr_poly
					(pts
						(arc
							(start -0.1778 -0.2794)
							(mid -0.249642 -0.249642)
							(end -0.2794 -0.1778)
						)
						(arc
							(start -0.2794 0.1778)
							(mid -0.249642 0.249642)
							(end -0.1778 0.2794)
						)
						(arc
							(start 0.1778 0.2794)
							(mid 0.249642 0.249642)
							(end 0.2794 0.1778)
						)
						(arc
							(start 0.2794 -0.1778)
							(mid 0.249642 -0.249642)
							(end 0.1778 -0.2794)
						)
					)
					(width 0)
					(fill yes)
				)
			)
		)
	)
	(footprint ""
		(layer "F.Cu")
		(at 24.764746 -276.4917)
		(property "Reference" "R206"
			(at 0 0 0)
			(layer "F.SilkS")
			(hide yes)
			(effects
				(font
					(size 1.27 1.27)
				)
			)
		)
		(property "Value" "1KR2F-3-GP"
			(at 0.064008 -3.993896 0)
			(unlocked yes)
			(layer "F.Fab")
			(hide yes)
			(effects
				(font
					(size 1.016 1.016)
					(thickness 0.1524)
				)
			)
		)
		(property "Device Type" "R402H16"
			(at 0.064008 -5.517896 0)
			(unlocked yes)
			(layer "F.Fab")
			(hide yes)
			(effects
				(font
					(size 1.016 1.016)
					(thickness 0.1524)
				)
			)
		)
		(duplicate_pad_numbers_are_jumpers no)
		(fp_line
			(start -0.508 -0.9398)
			(end -0.508 0.9398)
			(stroke
				(width 0.1524)
				(type default)
			)
			(layer "F.SilkS")
		)
		(fp_line
			(start 0.508 -0.9398)
			(end -0.508 -0.9398)
			(stroke
				(width 0.1524)
				(type default)
			)
			(layer "F.SilkS")
		)
		(fp_rect
			(start -0.508 0.9398)
			(end 0.508 -0.9398)
			(stroke
				(width 0)
				(type default)
			)
			(fill no)
			(layer "F.CrtYd")
		)
		(fp_rect
			(start -0.508 0.9398)
			(end 0.508 -0.9398)
			(stroke
				(width 0)
				(type default)
			)
			(fill no)
			(layer "F.Fab")
		)
		(pad "1" smd custom
			(at 0 -0.4445)
			(size 0.1397 0.1397)
			(layers "F.Cu" "F.Mask" "F.Paste")
			(net "P3V3")
			(options
				(clearance outline)
				(anchor circle)
			)
			(primitives
				(gr_poly
					(pts
						(arc
							(start -0.1778 -0.2794)
							(mid -0.249642 -0.249642)
							(end -0.2794 -0.1778)
						)
						(arc
							(start -0.2794 0.1778)
							(mid -0.249642 0.249642)
							(end -0.1778 0.2794)
						)
						(arc
							(start 0.1778 0.2794)
							(mid 0.249642 0.249642)
							(end 0.2794 0.1778)
						)
						(arc
							(start 0.2794 -0.1778)
							(mid 0.249642 -0.249642)
							(end 0.1778 -0.2794)
						)
					)
					(width 0)
					(fill yes)
				)
			)
		)
		(pad "2" smd custom
			(at 0 0.4445)
			(size 0.1397 0.1397)
			(layers "F.Cu" "F.Mask" "F.Paste")
			(net "SW_PWR_HDD7")
			(options
				(clearance outline)
				(anchor circle)
			)
			(primitives
				(gr_poly
					(pts
						(arc
							(start -0.1778 -0.2794)
							(mid -0.249642 -0.249642)
							(end -0.2794 -0.1778)
						)
						(arc
							(start -0.2794 0.1778)
							(mid -0.249642 0.249642)
							(end -0.1778 0.2794)
						)
						(arc
							(start 0.1778 0.2794)
							(mid 0.249642 0.249642)
							(end 0.2794 0.1778)
						)
						(arc
							(start 0.2794 -0.1778)
							(mid 0.249642 -0.249642)
							(end 0.1778 -0.2794)
						)
					)
					(width 0)
					(fill yes)
				)
			)
		)
	)
	(footprint ""
		(layer "F.Cu")
		(at 217.727784 -172.817028)
		(property "Reference" "C156"
			(at 0 0 0)
			(layer "F.SilkS")
			(hide yes)
			(effects
				(font
					(size 1.27 1.27)
				)
			)
		)
		(property "Value" "SCD01U50V2KX-1GP"
			(at 1.1811 -2.7051 0)
			(unlocked yes)
			(layer "F.Fab")
			(hide yes)
			(effects
				(font
					(size 1.016 1.016)
					(thickness 0.1524)
				)
			)
		)
		(property "Device Type" "C402H22"
			(at 1.1811 -4.2291 0)
			(unlocked yes)
			(layer "F.Fab")
			(hide yes)
			(effects
				(font
					(size 1.016 1.016)
					(thickness 0.1524)
				)
			)
		)
		(duplicate_pad_numbers_are_jumpers no)
		(fp_rect
			(start -0.4318 0.9525)
			(end 0.4318 -0.9525)
			(stroke
				(width 0)
				(type default)
			)
			(fill no)
			(layer "F.CrtYd")
		)
		(fp_rect
			(start -0.4318 0.9525)
			(end 0.4318 -0.9525)
			(stroke
				(width 0)
				(type default)
			)
			(fill no)
			(layer "F.Fab")
		)
		(pad "1" smd custom
			(at 0 -0.4445)
			(size 0.1524 0.1524)
			(layers "F.Cu" "F.Mask" "F.Paste")
			(net "HDD_PRSNT_NET3")
			(options
				(clearance outline)
				(anchor circle)
			)
			(primitives
				(gr_poly
					(pts
						(arc
							(start 0.3048 -0.2032)
							(mid 0.275042 -0.275042)
							(end 0.2032 -0.3048)
						)
						(arc
							(start -0.2032 -0.3048)
							(mid -0.275042 -0.275042)
							(end -0.3048 -0.2032)
						)
						(arc
							(start -0.3048 0.2032)
							(mid -0.275042 0.275042)
							(end -0.2032 0.3048)
						)
						(arc
							(start 0.2032 0.3048)
							(mid 0.275042 0.275042)
							(end 0.3048 0.2032)
						)
					)
					(width 0)
					(fill yes)
				)
			)
		)
		(pad "2" smd custom
			(at 0 0.4445)
			(size 0.1524 0.1524)
			(layers "F.Cu" "F.Mask" "F.Paste")
			(net "GND")
			(options
				(clearance outline)
				(anchor circle)
			)
			(primitives
				(gr_poly
					(pts
						(arc
							(start 0.3048 -0.2032)
							(mid 0.275042 -0.275042)
							(end 0.2032 -0.3048)
						)
						(arc
							(start -0.2032 -0.3048)
							(mid -0.275042 -0.275042)
							(end -0.3048 -0.2032)
						)
						(arc
							(start -0.3048 0.2032)
							(mid -0.275042 0.275042)
							(end -0.2032 0.3048)
						)
						(arc
							(start 0.2032 0.3048)
							(mid 0.275042 0.275042)
							(end 0.3048 0.2032)
						)
					)
					(width 0)
					(fill yes)
				)
			)
		)
	)
	(footprint ""
		(layer "F.Cu")
		(at 231.774746 -27.9527)
		(property "Reference" "PR5"
			(at 0 0 0)
			(layer "F.SilkS")
			(hide yes)
			(effects
				(font
					(size 1.27 1.27)
				)
			)
		)
		(property "Value" "10KR2F-2-GP"
			(at 0.064008 -3.993896 0)
			(unlocked yes)
			(layer "F.Fab")
			(hide yes)
			(effects
				(font
					(size 1.016 1.016)
					(thickness 0.1524)
				)
			)
		)
		(property "Device Type" "R402H16"
			(at 0.064008 -5.517896 0)
			(unlocked yes)
			(layer "F.Fab")
			(hide yes)
			(effects
				(font
					(size 1.016 1.016)
					(thickness 0.1524)
				)
			)
		)
		(duplicate_pad_numbers_are_jumpers no)
		(fp_line
			(start -0.508 -0.9398)
			(end -0.508 0.9398)
			(stroke
				(width 0.1524)
				(type default)
			)
			(layer "F.SilkS")
		)
		(fp_line
			(start 0.508 -0.9398)
			(end -0.508 -0.9398)
			(stroke
				(width 0.1524)
				(type default)
			)
			(layer "F.SilkS")
		)
		(fp_rect
			(start -0.508 0.9398)
			(end 0.508 -0.9398)
			(stroke
				(width 0)
				(type default)
			)
			(fill no)
			(layer "F.CrtYd")
		)
		(fp_rect
			(start -0.508 0.9398)
			(end 0.508 -0.9398)
			(stroke
				(width 0)
				(type default)
			)
			(fill no)
			(layer "F.Fab")
		)
		(pad "1" smd custom
			(at 0 -0.4445)
			(size 0.1397 0.1397)
			(layers "F.Cu" "F.Mask" "F.Paste")
			(net "P5VA_VREG")
			(options
				(clearance outline)
				(anchor circle)
			)
			(primitives
				(gr_poly
					(pts
						(arc
							(start -0.1778 -0.2794)
							(mid -0.249642 -0.249642)
							(end -0.2794 -0.1778)
						)
						(arc
							(start -0.2794 0.1778)
							(mid -0.249642 0.249642)
							(end -0.1778 0.2794)
						)
						(arc
							(start 0.1778 0.2794)
							(mid 0.249642 0.249642)
							(end 0.2794 0.1778)
						)
						(arc
							(start 0.2794 -0.1778)
							(mid 0.249642 -0.249642)
							(end 0.1778 -0.2794)
						)
					)
					(width 0)
					(fill yes)
				)
			)
		)
		(pad "2" smd custom
			(at 0 0.4445)
			(size 0.1397 0.1397)
			(layers "F.Cu" "F.Mask" "F.Paste")
			(net "P5VA_PGD")
			(options
				(clearance outline)
				(anchor circle)
			)
			(primitives
				(gr_poly
					(pts
						(arc
							(start -0.1778 -0.2794)
							(mid -0.249642 -0.249642)
							(end -0.2794 -0.1778)
						)
						(arc
							(start -0.2794 0.1778)
							(mid -0.249642 0.249642)
							(end -0.1778 0.2794)
						)
						(arc
							(start 0.1778 0.2794)
							(mid 0.249642 0.249642)
							(end 0.2794 0.1778)
						)
						(arc
							(start 0.2794 -0.1778)
							(mid 0.249642 -0.249642)
							(end 0.1778 -0.2794)
						)
					)
					(width 0)
					(fill yes)
				)
			)
		)
	)
	(footprint ""
		(layer "F.Cu")
		(at 73.659746 -400.3167 90)
		(property "Reference" "U20"
			(at 0 0 90)
			(layer "F.SilkS")
			(hide yes)
			(effects
				(font
					(size 1.27 1.27)
				)
			)
		)
		(property "Value" "P2003EVG-GP"
			(at 0 -11.1252 90)
			(unlocked yes)
			(layer "F.Fab")
			(hide yes)
			(effects
				(font
					(size 1.016 1.016)
					(thickness 0.1524)
				)
			)
		)
		(property "Device Type" "SOIC8H79"
			(at 0 -12.6492 90)
			(unlocked yes)
			(layer "F.Fab")
			(hide yes)
			(effects
				(font
					(size 1.016 1.016)
					(thickness 0.1524)
				)
			)
		)
		(duplicate_pad_numbers_are_jumpers no)
		(fp_line
			(start 2.1336 -1.4224)
			(end -2.7432 -1.4224)
			(stroke
				(width 0.1524)
				(type default)
			)
			(layer "F.SilkS")
		)
		(fp_line
			(start -2.7432 -1.4224)
			(end -2.7432 1.4224)
			(stroke
				(width 0.1524)
				(type default)
			)
			(layer "F.SilkS")
		)
		(fp_line
			(start -2.7432 -0.508)
			(end -2.2352 0)
			(stroke
				(width 0.1524)
				(type default)
			)
			(layer "F.SilkS")
		)
		(fp_line
			(start -2.2352 0)
			(end -2.7432 0.508)
			(stroke
				(width 0.1524)
				(type default)
			)
			(layer "F.SilkS")
		)
		(fp_line
			(start 2.1336 1.4224)
			(end 2.1336 -1.4224)
			(stroke
				(width 0.1524)
				(type default)
			)
			(layer "F.SilkS")
		)
		(fp_line
			(start -2.7432 1.4224)
			(end 2.1336 1.4224)
			(stroke
				(width 0.1524)
				(type default)
			)
			(layer "F.SilkS")
		)
		(fp_line
			(start -2.6162 3.429)
			(end -2.6162 1.4732)
			(stroke
				(width 0.4064)
				(type default)
			)
			(layer "F.SilkS")
		)
		(fp_poly
			(pts
				(xy 2.2098 -1.4224) (xy 2.2098 1.4224) (xy -2.2225 1.4224) (xy -2.2225 -1.4224)
			)
			(stroke
				(width 0)
				(type default)
			)
			(fill yes)
			(layer "F.SilkS")
		)
		(fp_rect
			(start -2.4511 2.9972)
			(end 2.4511 -2.9972)
			(stroke
				(width 0)
				(type default)
			)
			(fill no)
			(layer "F.CrtYd")
		)
		(fp_poly
			(pts
				(xy -2.8194 3.6322) (xy -2.8194 -3.6322) (xy 2.8194 -3.6322) (xy 2.8194 -2.2987) (xy 2.4511 -2.2987)
				(xy 2.4511 -2.9972) (xy -2.4511 -2.9972) (xy -2.4511 2.9972) (xy 2.4511 2.9972) (xy 2.4511 -2.286)
				(xy 2.8194 -2.286) (xy 2.8194 3.6322)
			)
			(stroke
				(width 0)
				(type default)
			)
			(fill no)
			(layer "F.CrtYd")
		)
		(fp_rect
			(start -2.8194 3.6322)
			(end 2.8194 -3.6322)
			(stroke
				(width 0)
				(type default)
			)
			(fill no)
			(layer "F.Fab")
		)
		(pad "1" smd rect
			(at -1.905 2.54 90)
			(size 0.635 1.651)
			(layers "F.Cu" "F.Mask" "F.Paste")
			(net "P12V")
		)
		(pad "2" smd rect
			(at -0.635 2.54 90)
			(size 0.635 1.651)
			(layers "F.Cu" "F.Mask" "F.Paste")
			(net "P12V")
		)
		(pad "3" smd rect
			(at 0.635 2.54 90)
			(size 0.635 1.651)
			(layers "F.Cu" "F.Mask" "F.Paste")
			(net "P12V")
		)
		(pad "4" smd rect
			(at 1.905 2.54 90)
			(size 0.635 1.651)
			(layers "F.Cu" "F.Mask" "F.Paste")
			(net "SW_HDD6_N")
		)
		(pad "5" smd rect
			(at 1.905 -2.54 90)
			(size 0.635 1.651)
			(layers "F.Cu" "F.Mask" "F.Paste")
			(net "P12V_HDD6")
		)
		(pad "6" smd rect
			(at 0.635 -2.54 90)
			(size 0.635 1.651)
			(layers "F.Cu" "F.Mask" "F.Paste")
			(net "P12V_HDD6")
		)
		(pad "7" smd rect
			(at -0.635 -2.54 90)
			(size 0.635 1.651)
			(layers "F.Cu" "F.Mask" "F.Paste")
			(net "P12V_HDD6")
		)
		(pad "8" smd rect
			(at -1.905 -2.54 90)
			(size 0.635 1.651)
			(layers "F.Cu" "F.Mask" "F.Paste")
			(net "P12V_HDD6")
		)
	)
	(footprint ""
		(layer "F.Cu")
		(at 28.447746 -274.9677 180)
		(property "Reference" "U22"
			(at 0 0 180)
			(layer "F.SilkS")
			(hide yes)
			(effects
				(font
					(size 1.27 1.27)
				)
			)
		)
		(property "Value" "74LVC1G08GW-1-GP"
			(at -2.3368 -8.6868 180)
			(unlocked yes)
			(layer "F.Fab")
			(hide yes)
			(effects
				(font
					(size 1.016 1.016)
					(thickness 0.1524)
				)
			)
		)
		(property "Device Type" "SC70-5H44"
			(at -2.3114 -10.414 180)
			(unlocked yes)
			(layer "F.Fab")
			(hide yes)
			(effects
				(font
					(size 1.016 1.016)
					(thickness 0.1524)
				)
			)
		)
		(duplicate_pad_numbers_are_jumpers no)
		(fp_line
			(start 1.3843 -1.8034)
			(end 1.3843 -1.1176)
			(stroke
				(width 0.3302)
				(type default)
			)
			(layer "F.SilkS")
		)
		(fp_line
			(start 1.27 1.7018)
			(end -1.27 1.7018)
			(stroke
				(width 0.1524)
				(type default)
			)
			(layer "F.SilkS")
		)
		(fp_line
			(start 1.27 -1.7018)
			(end 1.27 1.7018)
			(stroke
				(width 0.1524)
				(type default)
			)
			(layer "F.SilkS")
		)
		(fp_line
			(start 0.6604 -1.8034)
			(end 1.3843 -1.8034)
			(stroke
				(width 0.3302)
				(type default)
			)
			(layer "F.SilkS")
		)
		(fp_line
			(start -1.27 1.7018)
			(end -1.27 -1.7018)
			(stroke
				(width 0.1524)
				(type default)
			)
			(layer "F.SilkS")
		)
		(fp_line
			(start -1.27 -1.7018)
			(end 1.27 -1.7018)
			(stroke
				(width 0.1524)
				(type default)
			)
			(layer "F.SilkS")
		)
		(fp_rect
			(start -1.524 1.9558)
			(end 1.524 -1.9558)
			(stroke
				(width 0)
				(type default)
			)
			(fill no)
			(layer "F.CrtYd")
		)
		(fp_poly
			(pts
				(xy -1.524 -1.9558) (xy 1.524 -1.9558) (xy 1.524 1.9558) (xy -1.524 1.9558)
			)
			(stroke
				(width 0)
				(type default)
			)
			(fill no)
			(layer "F.Fab")
		)
		(pad "1" smd rect
			(at 0.65024 -0.8255 180)
			(size 0.4064 1.2192)
			(layers "F.Cu" "F.Mask" "F.Paste")
			(net "SAS2X28_B_HDD7_FLT")
		)
		(pad "2" smd rect
			(at 0 -0.8255 180)
			(size 0.4064 1.2192)
			(layers "F.Cu" "F.Mask" "F.Paste")
			(net "SAS2X28_A_HDD7_FLT")
		)
		(pad "3" smd rect
			(at -0.65024 -0.8255 180)
			(size 0.4064 1.2192)
			(layers "F.Cu" "F.Mask" "F.Paste")
			(net "GND")
		)
		(pad "4" smd rect
			(at -0.65024 0.8255 180)
			(size 0.4064 1.2192)
			(layers "F.Cu" "F.Mask" "F.Paste")
			(net "FLT_HDD7_DRIVE")
		)
		(pad "5" smd rect
			(at 0.65024 0.8255 180)
			(size 0.4064 1.2192)
			(layers "F.Cu" "F.Mask" "F.Paste")
			(net "P3V3")
		)
	)
)
